# S9S_MB_2U (Grand Teton) — schematic netlist excerpt (pin names and nets, part order shuffled) for the footprints in the layout excerpt that follows; sources: Cadence DE-HDL packaged netlist, KiCad conversion of 03242023_DA0F0TMBIJ0_F0T_Motherboard_J_brd_V01_OCP.brd

J32  SCONN288_ADR50017P087CC  SCONN288_ADR50017-P087CC IO  pkg DDR288S_1-1VXB  page 113
  VIN_BULK0  = P12V_S3_AUX_CPU1_NVDIMM
  RFU0  = TP_CHH_CPU1_DIMM2_FRU_0
  VIN_MGMT  = P3V3_AUX
  HSCL  = I3C_SPD_DDREFGH_CPU1_LVC1_SCL_7
  HSDA  = I3C_SPD_DDREFGH_CPU1_LVC1_SDA
  VSS0  = GND
  DQ0_A  = M_H_CPU1_SA_DQ<0>
  VSS1  = GND
  DQ1_A  = M_H_CPU1_SA_DQ<1>
  VSS2  = GND
  DQS0_A_T  = M_H_CPU1_SA_DQS_DP<0>
  DQS0_A_C  = M_H_CPU1_SA_DQS_DN<0>
  VSS3  = GND
  DQ4_A  = M_H_CPU1_SA_DQ<4>
  VSS4  = GND
  DQ5_A  = M_H_CPU1_SA_DQ<5>
  VSS5  = GND
  DQ8_A  = M_H_CPU1_SA_DQ<8>
  VSS6  = GND
  DQ9_A  = M_H_CPU1_SA_DQ<9>
  VSS7  = GND
  DQS1_A_T  = M_H_CPU1_SA_DQS_DP<1>
  DQS1_A_C  = M_H_CPU1_SA_DQS_DN<1>
  VSS8  = GND
  DQ12_A  = M_H_CPU1_SA_DQ<12>
  VSS9  = GND
  DQ13_A  = M_H_CPU1_SA_DQ<13>
  VSS10  = GND
  DQ16_A  = M_H_CPU1_SA_DQ<16>
  VSS11  = GND
  DQ17_A  = M_H_CPU1_SA_DQ<17>
  VSS12  = GND
  DQS2_A_T  = M_H_CPU1_SA_DQS_DP<2>
  DQS2_A_C  = M_H_CPU1_SA_DQS_DN<2>
  VSS13  = GND
  DQ20_A  = M_H_CPU1_SA_DQ<20>
  VSS14  = GND
  DQ21_A  = M_H_CPU1_SA_DQ<21>
  VSS15  = GND
  DQ24_A  = M_H_CPU1_SA_DQ<24>
  VSS16  = GND
  DQ25_A  = M_H_CPU1_SA_DQ<25>
  VSS17  = GND
  DQS3_A_T  = M_H_CPU1_SA_DQS_DP<3>
  DQS3_A_C  = M_H_CPU1_SA_DQS_DN<3>
  VSS18  = GND
  DQ28_A  = M_H_CPU1_SA_DQ<28>
  VSS19  = GND
  DQ29_A  = M_H_CPU1_SA_DQ<29>
  VSS20  = GND
  CB0_A  = M_H_CPU1_SA_CB<0>
  VSS21  = GND
  CB1_A  = M_H_CPU1_SA_CB<1>
  VSS22  = GND
  DQS4_A_T  = M_H_CPU1_SA_DQS_DP<4>
  DQS4_A_C  = M_H_CPU1_SA_DQS_DN<4>
  VSS23  = GND
  CB4_A  = M_H_CPU1_SA_CB<4>
  VSS24  = GND
  CB5_A  = M_H_CPU1_SA_CB<5>
  VSS25  = GND
  ALERT_N  = M_H_CPU1_ALERT_N
  VSS26  = GND
  CS0_A_N  = M_H_CPU1_SA_CS_N<2>
  VSS27  = GND
  CA0_A  = M_H_CPU1_SA_CA<0>
  VSS28  = GND
  CA2_A  = M_H_CPU1_SA_CA<2>
  VSS29  = GND
  CA4_A  = M_H_CPU1_SA_CA<4>
  VSS30  = GND
  CA6_A  = M_H_CPU1_SA_CA<6>
  VSS31  = GND
  PAR_A  = M_H_CPU1_SA_PAR
  VSS32  = GND
  CA0_B  = M_H_CPU1_SB_CA<0>
  VSS33  = GND
  CA2_B  = M_H_CPU1_SB_CA<2>
  VSS34  = GND
  CA4_B  = M_H_CPU1_SB_CA<4>
  VSS35  = GND
  CA6_B  = M_H_CPU1_SB_CA<6>
  VSS36  = GND
  CS0_B_N  = M_H_CPU1_SB_CS_N<2>
  VSS37  = GND
  \lbd||rsp_a_n\  = M_H_CPU1_SA_RSP<1>
  \lbs||rsp_b_n\  = M_H_CPU1_SB_RSP<1>
  VSS38  = GND
  CB4_B  = M_H_CPU1_SB_CB<4>
  VSS39  = GND
  CB5_B  = M_H_CPU1_SB_CB<5>
  VSS40  = GND
  \dqs9_b_t||tdqs9_b_t||dbi4_b_n\  = M_H_CPU1_SB_DQS_DP<9>
  \dqs9_b_c||tdqs9_b_c\  = M_H_CPU1_SB_DQS_DN<9>
  VSS41  = GND
  CB0_B  = M_H_CPU1_SB_CB<0>
  VSS42  = GND
  CB1_B  = M_H_CPU1_SB_CB<1>
  VSS43  = GND
  DQ0_B  = M_H_CPU1_SB_DQ<0>
  VSS44  = GND
  DQ1_B  = M_H_CPU1_SB_DQ<1>
  VSS45  = GND
  DQS0_B_T  = M_H_CPU1_SB_DQS_DP<0>
  DQS0_B_C  = M_H_CPU1_SB_DQS_DN<0>
  VSS46  = GND
  DQ4_B  = M_H_CPU1_SB_DQ<4>
  VSS47  = GND
  DQ5_B  = M_H_CPU1_SB_DQ<5>
  VSS48  = GND
  DQ8_B  = M_H_CPU1_SB_DQ<8>
  VSS49  = GND
  DQ9_B  = M_H_CPU1_SB_DQ<9>
  VSS50  = GND
  DQS1_B_T  = M_H_CPU1_SB_DQS_DP<1>
  DQS1_B_C  = M_H_CPU1_SB_DQS_DN<1>
  VSS51  = GND
  DQ12_B  = M_H_CPU1_SB_DQ<12>
  VSS52  = GND
  DQ13_B  = M_H_CPU1_SB_DQ<13>
  VSS53  = GND
  DQ16_B  = M_H_CPU1_SB_DQ<16>
  VSS54  = GND
  DQ17_B  = M_H_CPU1_SB_DQ<17>
  VSS55  = GND
  DQS2_B_T  = M_H_CPU1_SB_DQS_DP<2>
  DQS2_B_C  = M_H_CPU1_SB_DQS_DN<2>
  VSS56  = GND
  DQ20_B  = M_H_CPU1_SB_DQ<20>
  VSS57  = GND
  DQ21_B  = M_H_CPU1_SB_DQ<21>
  VSS58  = GND
  DQ24_B  = M_H_CPU1_SB_DQ<24>
  VSS59  = GND
  DQ25_B  = M_H_CPU1_SB_DQ<25>
  VSS60  = GND
  DQS3_B_T  = M_H_CPU1_SB_DQS_DP<3>
  DQS3_B_C  = M_H_CPU1_SB_DQS_DN<3>
  VSS61  = GND
  DQ28_B  = M_H_CPU1_SB_DQ<28>
  VSS62  = GND
  DQ29_B  = M_H_CPU1_SB_DQ<29>
  VSS63  = GND
  RFU1  = TP_CHH_CPU1_DIMM2_FRU_1
  VIN_BULK1  = P12V_S3_AUX_CPU1_NVDIMM
  VIN_BULK2  = P12V_S3_AUX_CPU1_NVDIMM
  \pwr_good||fail_n\  = PWRGD_CHH_CPU1_DIMM2
  HSA  = PD_CHH_CPU1_DIMM2_SAA
  RFU2  = TP_CHH_CPU1_DIMM2_FRU_2
  RFU3  = TP_CHH_CPU1_DIMM2_FRU_3
  VSS64  = GND
  DQ2_A  = M_H_CPU1_SA_DQ<2>
  VSS65  = GND
  DQ3_A  = M_H_CPU1_SA_DQ<3>
  VSS66  = GND
  \dqs5_a_c||tdqs5_a_c||dqs5_a_t||tdqs5_a_t\  = M_H_CPU1_SA_DQS_DN<5>
  \dqs5_a_t||tdqs5_a_t\  = M_H_CPU1_SA_DQS_DP<5>
  VSS67  = GND
  DQ6_A  = M_H_CPU1_SA_DQ<6>
  VSS68  = GND
  DQ7_A  = M_H_CPU1_SA_DQ<7>
  VSS69  = GND
  DQ10_A  = M_H_CPU1_SA_DQ<10>
  VSS70  = GND
  DQ11_A  = M_H_CPU1_SA_DQ<11>
  VSS71  = GND
  \dqs6_a_c||tdqs6_a_c||dqs6_a_t||tdqs6_a_t\  = M_H_CPU1_SA_DQS_DN<6>
  \dqs6_a_t||tdqs6_a_t\  = M_H_CPU1_SA_DQS_DP<6>
  VSS72  = GND
  DQ14_A  = M_H_CPU1_SA_DQ<14>
  VSS73  = GND
  DQ15_A  = M_H_CPU1_SA_DQ<15>
  VSS74  = GND
  DQ18_A  = M_H_CPU1_SA_DQ<18>
  VSS75  = GND
  DQ19_A  = M_H_CPU1_SA_DQ<19>
  VSS76  = GND
  \dqs7_a_c||tdqs7_a_c\  = M_H_CPU1_SA_DQS_DN<7>
  \dqs7_a_t||tdqs7_a_t\  = M_H_CPU1_SA_DQS_DP<7>
  VSS77  = GND
  DQ22_A  = M_H_CPU1_SA_DQ<22>
  VSS78  = GND
  DQ23_A  = M_H_CPU1_SA_DQ<23>
  VSS79  = GND
  DQ26_A  = M_H_CPU1_SA_DQ<26>
  VSS80  = GND
  DQ27_A  = M_H_CPU1_SA_DQ<27>
  VSS81  = GND
  \dqs8_a_c||tdqs8_a_c\  = M_H_CPU1_SA_DQS_DN<8>
  \dqs8_a_t||tdqs8_a_t\  = M_H_CPU1_SA_DQS_DP<8>
  VSS82  = GND
  DQ30_A  = M_H_CPU1_SA_DQ<30>
  VSS83  = GND
  DQ31_A  = M_H_CPU1_SA_DQ<31>
  VSS84  = GND
  CB2_A  = M_H_CPU1_SA_CB<2>
  VSS85  = GND
  CB3_A  = M_H_CPU1_SA_CB<3>
  VSS86  = GND
  \dqs9_a_c||tdqs9_a_c\  = M_H_CPU1_SA_DQS_DN<9>
  \dqs9_a_t||tdqs9_a_t\  = M_H_CPU1_SA_DQS_DP<9>
  VSS87  = GND
  CB6_A  = M_H_CPU1_SA_CB<6>
  VSS88  = GND
  CB7_A  = M_H_CPU1_SA_CB<7>
  VSS89  = GND
  RESET_N  = RST_M_GH_CPU1_FPGA_N
  VSS90  = GND
  CS1_A_N  = M_H_CPU1_SA_CS_N<3>
  VSS91  = GND
  CA1_A  = M_H_CPU1_SA_CA<1>
  VSS92  = GND
  CA3_A  = M_H_CPU1_SA_CA<3>
  VSS93  = GND
  CA5_A  = M_H_CPU1_SA_CA<5>
  VSS94  = GND
  CK_T  = M_H_CPU1_CLK_DP<1>
  CK_C  = M_H_CPU1_CLK_DN<1>
  VSS95  = GND
  RFU4  = TP_CHH_CPU1_DIMM2_FRU_4
  CA1_B  = M_H_CPU1_SB_CA<1>
  VSS96  = GND
  CA3_B  = M_H_CPU1_SB_CA<3>
  VSS97  = GND
  CA5_B  = M_H_CPU1_SB_CA<5>
  VSS98  = GND
  PAR_B  = M_H_CPU1_SB_PAR
  VSS99  = GND
  CS1_B_N  = M_H_CPU1_SB_CS_N<3>
  VSS100  = GND
  RFU5  = TP_CHH_CPU1_DIMM2_FRU_5
  RFU6  = TP_CHH_CPU1_DIMM2_FRU_6
  VSS101  = GND
  CB6_B  = M_H_CPU1_SB_CB<6>
  VSS102  = GND
  CB7_B  = M_H_CPU1_SB_CB<7>
  VSS103  = GND
  DQS4_B_C  = M_H_CPU1_SB_DQS_DN<4>
  DQS4_B_T  = M_H_CPU1_SB_DQS_DP<4>
  VSS104  = GND
  CB2_B  = M_H_CPU1_SB_CB<2>
  VSS105  = GND
  CB3_B  = M_H_CPU1_SB_CB<3>
  VSS106  = GND
  DQ2_B  = M_H_CPU1_SB_DQ<2>
  VSS107  = GND
  DQ3_B  = M_H_CPU1_SB_DQ<3>
  VSS108  = GND
  \dqs5_b_c||tdqs5_b_c\  = M_H_CPU1_SB_DQS_DN<5>
  \dqs5_b_t||tdqs5_b_t\  = M_H_CPU1_SB_DQS_DP<5>
  VSS109  = GND
  DQ6_B  = M_H_CPU1_SB_DQ<6>
  VSS110  = GND
  DQ7_B  = M_H_CPU1_SB_DQ<7>
  VSS111  = GND
  DQ10_B  = M_H_CPU1_SB_DQ<10>
  VSS112  = GND
  DQ11_B  = M_H_CPU1_SB_DQ<11>
  VSS113  = GND
  \dqs6_b_c||tdqs6_b_c\  = M_H_CPU1_SB_DQS_DN<6>
  \dqs6_b_t||tdqs6_b_t\  = M_H_CPU1_SB_DQS_DP<6>
  VSS114  = GND
  DQ14_B  = M_H_CPU1_SB_DQ<14>
  VSS115  = GND
  DQ15_B  = M_H_CPU1_SB_DQ<15>
  VSS116  = GND
  DQ18_B  = M_H_CPU1_SB_DQ<18>
  VSS117  = GND
  DQ19_B  = M_H_CPU1_SB_DQ<19>
  VSS118  = GND
  \dqs7_b_c||tdqs7_b_c\  = M_H_CPU1_SB_DQS_DN<7>
  \dqs7_b_t||tdqs7_b_t\  = M_H_CPU1_SB_DQS_DP<7>
  VSS119  = GND
  DQ22_B  = M_H_CPU1_SB_DQ<22>
  VSS120  = GND
  DQ23_B  = M_H_CPU1_SB_DQ<23>
  VSS121  = GND
  DQ26_B  = M_H_CPU1_SB_DQ<26>
  VSS122  = GND
  DQ27_B  = M_H_CPU1_SB_DQ<27>
  VSS123  = GND
  \dqs8_b_c||tdqs8_b_c\  = M_H_CPU1_SB_DQS_DN<8>
  \dqs8_b_t||tdqs8_b_t\  = M_H_CPU1_SB_DQS_DP<8>
  VSS124  = GND
  DQ30_B  = M_H_CPU1_SB_DQ<30>
  VSS125  = GND
  DQ31_B  = M_H_CPU1_SB_DQ<31>
  VSS126  = GND
  G1  = GND
  G2  = GND
  G3  = GND

(kicad_pcb
	(version 20260206)
	(generator "pcbnew")
	(generator_version "10.0")
	(general
		(thickness 1.6)
		(legacy_teardrops no)
	)
	(paper "A4")
	(title_block
		(title "03242023_DA0F0TMBIJ0_F0T_Motherboard_J_brd_V01_OCP.brd")
		(comment 1 "Grand Teton / footprint 3133 of 6105 (J32), pads 138-182 of 291")
	)
	(layers
		(0 "F.Cu" signal "TOP")
		(4 "In1.Cu" signal "GND")
		(6 "In2.Cu" signal "IN1")
		(8 "In3.Cu" signal "GND1")
		(10 "In4.Cu" signal "IN2")
		(12 "In5.Cu" signal "GND2")
		(14 "In6.Cu" signal "IN3")
		(16 "In7.Cu" signal "GND3")
		(18 "In8.Cu" signal "VCC")
		(20 "In9.Cu" signal "VCC1")
		(22 "In10.Cu" signal "GND4")
		(24 "In11.Cu" signal "IN4")
		(26 "In12.Cu" signal "GND5")
		(28 "In13.Cu" signal "IN5")
		(30 "In14.Cu" signal "GND6")
		(32 "In15.Cu" signal "IN6")
		(34 "In16.Cu" signal "GND7")
		(2 "B.Cu" signal "BOTTOM")
		(9 "F.Adhes" user "F.Adhesive")
		(11 "B.Adhes" user "B.Adhesive")
		(13 "F.Paste" user "Package Geometry/Pastemask Top")
		(15 "B.Paste" user "Package Geometry/Pastemask Bottom")
		(5 "F.SilkS" user "Ref Des/Silkscreen Top")
		(7 "B.SilkS" user "Ref Des/Silkscreen Bottom")
		(1 "F.Mask" user "Board Geometry/Soldermask Top")
		(3 "B.Mask" user "Board Geometry/Soldermask Bottom")
		(17 "Dwgs.User" user "User.Drawings")
		(19 "Cmts.User" user "User.Comments")
		(21 "Eco1.User" user "User.Eco1")
		(23 "Eco2.User" user "User.Eco2")
		(25 "Edge.Cuts" user "Board Geometry/Outline")
		(27 "Margin" user)
		(31 "F.CrtYd" user "Package Geometry/Place Bound Top")
		(29 "B.CrtYd" user "Package Geometry/Place Bound Bottom")
		(35 "F.Fab" user "Ref Des/Assembly Top")
		(33 "B.Fab" user "Ref Des/Assembly Bottom")
	)
	(footprint ""
		(layer "F.Cu")
		(at 206.12608 -258.091686)
		(property "Reference" "J32"
			(at 0.68834 -81.826608 0)
			(unlocked yes)
			(layer "F.SilkS")
			(effects
				(font
					(size 0.7874 0.5842)
					(thickness 0.1524)
				)
				(justify left)
			)
		)
		(property "Value" ""
			(at 0 0 0)
			(layer "F.Fab")
			(effects
				(font
					(size 1.27 1.27)
				)
			)
		)
		(duplicate_pad_numbers_are_jumpers no)
		(pad "138" smd rect
			(at -2.050034 58.224928 270)
			(size 0.519938 1.4986)
			(layers "F.Cu" "F.Mask" "F.Paste")
			(net "M_H_CPU1_SB_DQS_DN<3>")
		)
		(pad "139" smd rect
			(at -2.050034 59.075066 270)
			(size 0.519938 1.4986)
			(layers "F.Cu" "F.Mask" "F.Paste")
			(net "GND")
		)
		(pad "140" smd rect
			(at -2.050034 59.92495 270)
			(size 0.519938 1.4986)
			(layers "F.Cu" "F.Mask" "F.Paste")
			(net "M_H_CPU1_SB_DQ<28>")
		)
		(pad "141" smd rect
			(at -2.050034 60.775088 270)
			(size 0.519938 1.4986)
			(layers "F.Cu" "F.Mask" "F.Paste")
			(net "GND")
		)
		(pad "142" smd rect
			(at -2.050034 61.624972 270)
			(size 0.519938 1.4986)
			(layers "F.Cu" "F.Mask" "F.Paste")
			(net "M_H_CPU1_SB_DQ<29>")
		)
		(pad "143" smd rect
			(at -2.050034 62.47511 270)
			(size 0.519938 1.4986)
			(layers "F.Cu" "F.Mask" "F.Paste")
			(net "GND")
		)
		(pad "144" smd rect
			(at -2.050034 63.324994 270)
			(size 0.519938 1.4986)
			(layers "F.Cu" "F.Mask" "F.Paste")
			(net "TP_CHH_CPU1_DIMM2_FRU_1")
		)
		(pad "145" smd rect
			(at 2.050034 -63.324994 270)
			(size 0.519938 1.4986)
			(layers "F.Cu" "F.Mask" "F.Paste")
			(net "P12V_S3_AUX_CPU1_NVDIMM")
		)
		(pad "146" smd rect
			(at 2.050034 -62.47511 270)
			(size 0.519938 1.4986)
			(layers "F.Cu" "F.Mask" "F.Paste")
			(net "P12V_S3_AUX_CPU1_NVDIMM")
		)
		(pad "147" smd rect
			(at 2.050034 -61.624972 270)
			(size 0.519938 1.4986)
			(layers "F.Cu" "F.Mask" "F.Paste")
			(net "PWRGD_CHH_CPU1_DIMM2")
		)
		(pad "148" smd rect
			(at 2.050034 -60.775088 270)
			(size 0.519938 1.4986)
			(layers "F.Cu" "F.Mask" "F.Paste")
			(net "PD_CHH_CPU1_DIMM2_SAA")
		)
		(pad "149" smd rect
			(at 2.050034 -59.92495 270)
			(size 0.519938 1.4986)
			(layers "F.Cu" "F.Mask" "F.Paste")
			(net "TP_CHH_CPU1_DIMM2_FRU_2")
		)
		(pad "150" smd rect
			(at 2.050034 -59.075066 270)
			(size 0.519938 1.4986)
			(layers "F.Cu" "F.Mask" "F.Paste")
			(net "TP_CHH_CPU1_DIMM2_FRU_3")
		)
		(pad "151" smd rect
			(at 2.050034 -58.224928 270)
			(size 0.519938 1.4986)
			(layers "F.Cu" "F.Mask" "F.Paste")
			(net "GND")
		)
		(pad "152" smd rect
			(at 2.050034 -57.375044 270)
			(size 0.519938 1.4986)
			(layers "F.Cu" "F.Mask" "F.Paste")
			(net "M_H_CPU1_SA_DQ<2>")
		)
		(pad "153" smd rect
			(at 2.050034 -56.524906 270)
			(size 0.519938 1.4986)
			(layers "F.Cu" "F.Mask" "F.Paste")
			(net "GND")
		)
		(pad "154" smd rect
			(at 2.050034 -55.675022 270)
			(size 0.519938 1.4986)
			(layers "F.Cu" "F.Mask" "F.Paste")
			(net "M_H_CPU1_SA_DQ<3>")
		)
		(pad "155" smd rect
			(at 2.050034 -54.824884 270)
			(size 0.519938 1.4986)
			(layers "F.Cu" "F.Mask" "F.Paste")
			(net "GND")
		)
		(pad "156" smd rect
			(at 2.050034 -53.975 270)
			(size 0.519938 1.4986)
			(layers "F.Cu" "F.Mask" "F.Paste")
			(net "M_H_CPU1_SA_DQS_DN<5>")
		)
		(pad "157" smd rect
			(at 2.050034 -53.125116 270)
			(size 0.519938 1.4986)
			(layers "F.Cu" "F.Mask" "F.Paste")
			(net "M_H_CPU1_SA_DQS_DP<5>")
		)
		(pad "158" smd rect
			(at 2.050034 -52.274978 270)
			(size 0.519938 1.4986)
			(layers "F.Cu" "F.Mask" "F.Paste")
			(net "GND")
		)
		(pad "159" smd rect
			(at 2.050034 -51.425094 270)
			(size 0.519938 1.4986)
			(layers "F.Cu" "F.Mask" "F.Paste")
			(net "M_H_CPU1_SA_DQ<6>")
		)
		(pad "160" smd rect
			(at 2.050034 -50.574956 270)
			(size 0.519938 1.4986)
			(layers "F.Cu" "F.Mask" "F.Paste")
			(net "GND")
		)
		(pad "161" smd rect
			(at 2.050034 -49.725072 270)
			(size 0.519938 1.4986)
			(layers "F.Cu" "F.Mask" "F.Paste")
			(net "M_H_CPU1_SA_DQ<7>")
		)
		(pad "162" smd rect
			(at 2.050034 -48.874934 270)
			(size 0.519938 1.4986)
			(layers "F.Cu" "F.Mask" "F.Paste")
			(net "GND")
		)
		(pad "163" smd rect
			(at 2.050034 -48.02505 270)
			(size 0.519938 1.4986)
			(layers "F.Cu" "F.Mask" "F.Paste")
			(net "M_H_CPU1_SA_DQ<10>")
		)
		(pad "164" smd rect
			(at 2.050034 -47.174912 270)
			(size 0.519938 1.4986)
			(layers "F.Cu" "F.Mask" "F.Paste")
			(net "GND")
		)
		(pad "165" smd rect
			(at 2.050034 -46.325028 270)
			(size 0.519938 1.4986)
			(layers "F.Cu" "F.Mask" "F.Paste")
			(net "M_H_CPU1_SA_DQ<11>")
		)
		(pad "166" smd rect
			(at 2.050034 -45.47489 270)
			(size 0.519938 1.4986)
			(layers "F.Cu" "F.Mask" "F.Paste")
			(net "GND")
		)
		(pad "167" smd rect
			(at 2.050034 -44.625006 270)
			(size 0.519938 1.4986)
			(layers "F.Cu" "F.Mask" "F.Paste")
			(net "M_H_CPU1_SA_DQS_DN<6>")
		)
		(pad "168" smd rect
			(at 2.050034 -43.775122 270)
			(size 0.519938 1.4986)
			(layers "F.Cu" "F.Mask" "F.Paste")
			(net "M_H_CPU1_SA_DQS_DP<6>")
		)
		(pad "169" smd rect
			(at 2.050034 -42.924984 270)
			(size 0.519938 1.4986)
			(layers "F.Cu" "F.Mask" "F.Paste")
			(net "GND")
		)
		(pad "170" smd rect
			(at 2.050034 -42.0751 270)
			(size 0.519938 1.4986)
			(layers "F.Cu" "F.Mask" "F.Paste")
			(net "M_H_CPU1_SA_DQ<14>")
		)
		(pad "171" smd rect
			(at 2.050034 -41.224962 270)
			(size 0.519938 1.4986)
			(layers "F.Cu" "F.Mask" "F.Paste")
			(net "GND")
		)
		(pad "172" smd rect
			(at 2.050034 -40.375078 270)
			(size 0.519938 1.4986)
			(layers "F.Cu" "F.Mask" "F.Paste")
			(net "M_H_CPU1_SA_DQ<15>")
		)
		(pad "173" smd rect
			(at 2.050034 -39.52494 270)
			(size 0.519938 1.4986)
			(layers "F.Cu" "F.Mask" "F.Paste")
			(net "GND")
		)
		(pad "174" smd rect
			(at 2.050034 -38.675056 270)
			(size 0.519938 1.4986)
			(layers "F.Cu" "F.Mask" "F.Paste")
			(net "M_H_CPU1_SA_DQ<18>")
		)
		(pad "175" smd rect
			(at 2.050034 -37.824918 270)
			(size 0.519938 1.4986)
			(layers "F.Cu" "F.Mask" "F.Paste")
			(net "GND")
		)
		(pad "176" smd rect
			(at 2.050034 -36.975034 270)
			(size 0.519938 1.4986)
			(layers "F.Cu" "F.Mask" "F.Paste")
			(net "M_H_CPU1_SA_DQ<19>")
		)
		(pad "177" smd rect
			(at 2.050034 -36.124896 270)
			(size 0.519938 1.4986)
			(layers "F.Cu" "F.Mask" "F.Paste")
			(net "GND")
		)
		(pad "178" smd rect
			(at 2.050034 -35.275012 270)
			(size 0.519938 1.4986)
			(layers "F.Cu" "F.Mask" "F.Paste")
			(net "M_H_CPU1_SA_DQS_DN<7>")
		)
		(pad "179" smd rect
			(at 2.050034 -34.425128 270)
			(size 0.519938 1.4986)
			(layers "F.Cu" "F.Mask" "F.Paste")
			(net "M_H_CPU1_SA_DQS_DP<7>")
		)
		(pad "180" smd rect
			(at 2.050034 -33.57499 270)
			(size 0.519938 1.4986)
			(layers "F.Cu" "F.Mask" "F.Paste")
			(net "GND")
		)
		(pad "181" smd rect
			(at 2.050034 -32.725106 270)
			(size 0.519938 1.4986)
			(layers "F.Cu" "F.Mask" "F.Paste")
			(net "M_H_CPU1_SA_DQ<22>")
		)
		(pad "182" smd rect
			(at 2.050034 -31.874968 270)
			(size 0.519938 1.4986)
			(layers "F.Cu" "F.Mask" "F.Paste")
			(net "GND")
		)
	)
)
